# SDI-MIPI Bridge — KiCad project settings (.kicad_pro: net classes, design rules, text variables)
{
  "board": {
    "3dviewports": [],
    "design_settings": {
      "defaults": {
        "board_outline_line_width": 0.049999999999999996,
        "copper_line_width": 0.19999999999999998,
        "copper_text_italic": false,
        "copper_text_size_h": 1.5,
        "copper_text_size_v": 1.5,
        "copper_text_thickness": 0.3,
        "copper_text_upright": false,
        "courtyard_line_width": 0.049999999999999996,
        "dimension_precision": 4,
        "dimension_units": 3,
        "dimensions": {
          "arrow_length": 1270000,
          "extension_offset": 500000,
          "keep_text_aligned": true,
          "suppress_zeroes": false,
          "text_position": 0,
          "units_format": 1
        },
        "fab_line_width": 0.09999999999999999,
        "fab_text_italic": false,
        "fab_text_size_h": 1.0,
        "fab_text_size_v": 1.0,
        "fab_text_thickness": 0.15,
        "fab_text_upright": false,
        "other_line_width": 0.09999999999999999,
        "other_text_italic": false,
        "other_text_size_h": 1.0,
        "other_text_size_v": 1.0,
        "other_text_thickness": 0.15,
        "other_text_upright": false,
        "pads": {
          "drill": 2.5,
          "height": 4.4,
          "width": 4.4
        },
        "silk_line_width": 0.09999999999999999,
        "silk_text_italic": false,
        "silk_text_size_h": 0.7999999999999999,
        "silk_text_size_v": 0.7999999999999999,
        "silk_text_thickness": 0.12,
        "silk_text_upright": false,
        "zones": {
          "45_degree_only": false,
          "min_clearance": 0.15
        }
      },
      "diff_pair_dimensions": [
        {
          "gap": 0.0,
          "via_gap": 0.0,
          "width": 0.0
        }
      ],
      "drc_exclusions": [],
      "meta": {
        "filename": "board_design_settings.json",
        "version": 2
      },
      "rule_severities": {
        "annular_width": "error",
        "clearance": "error",
        "connection_width": "warning",
        "copper_edge_clearance": "error",
        "copper_sliver": "warning",
        "courtyards_overlap": "error",
        "diff_pair_gap_out_of_range": "error",
        "diff_pair_uncoupled_length_too_long": "error",
        "drill_out_of_range": "error",
        "duplicate_footprints": "warning",
        "extra_footprint": "warning",
        "footprint": "error",
        "footprint_type_mismatch": "error",
        "hole_clearance": "error",
        "hole_near_hole": "error",
        "invalid_outline": "error",
        "isolated_copper": "warning",
        "item_on_disabled_layer": "error",
        "items_not_allowed": "error",
        "length_out_of_range": "error",
        "lib_footprint_issues": "warning",
        "lib_footprint_mismatch": "warning",
        "malformed_courtyard": "error",
        "microvia_drill_out_of_range": "error",
        "missing_courtyard": "ignore",
        "missing_footprint": "warning",
        "net_conflict": "warning",
        "npth_inside_courtyard": "ignore",
        "padstack": "error",
        "pth_inside_courtyard": "ignore",
        "shorting_items": "error",
        "silk_edge_clearance": "warning",
        "silk_over_copper": "warning",
        "silk_overlap": "warning",
        "skew_out_of_range": "error",
        "solder_mask_bridge": "error",
        "starved_thermal": "error",
        "text_height": "warning",
        "text_thickness": "warning",
        "through_hole_pad_without_hole": "error",
        "too_many_vias": "error",
        "track_dangling": "warning",
        "track_width": "error",
        "tracks_crossing": "error",
        "unconnected_items": "error",
        "unresolved_variable": "error",
        "via_dangling": "warning",
        "zones_intersect": "error"
      },
      "rule_severitieslegacy_courtyards_overlap": true,
      "rule_severitieslegacy_no_courtyard_defined": false,
      "rules": {
        "allow_blind_buried_vias": false,
        "allow_microvias": false,
        "max_error": 0.005,
        "min_clearance": 0.0,
        "min_connection": 0.0,
        "min_copper_edge_clearance": 0.024999999999999998,
        "min_hole_clearance": 0.25,
        "min_hole_to_hole": 0.25,
        "min_microvia_diameter": 0.09999999999999999,
        "min_microvia_drill": 0.09999999999999999,
        "min_resolved_spokes": 2,
        "min_silk_clearance": 0.0,
        "min_text_height": 0.7999999999999999,
        "min_text_thickness": 0.08,
        "min_through_hole_diameter": 0.15,
        "min_track_width": 0.09999999999999999,
        "min_via_annular_width": 0.049999999999999996,
        "min_via_diameter": 0.5499999999999999,
        "solder_mask_to_copper_clearance": 0.0,
        "use_height_for_length_calcs": true
      },
      "teardrop_options": [
        {
          "td_allow_use_two_tracks": true,
          "td_curve_segcount": 5,
          "td_on_pad_in_zone": false,
          "td_onpadsmd": true,
          "td_onroundshapesonly": false,
          "td_ontrackend": false,
          "td_onviapad": true
        }
      ],
      "teardrop_parameters": [
        {
          "td_curve_segcount": 0,
          "td_height_ratio": 1.0,
          "td_length_ratio": 0.5,
          "td_maxheight": 2.0,
          "td_maxlen": 1.0,
          "td_target_name": "td_round_shape",
          "td_width_to_size_filter_ratio": 0.9
        },
        {
          "td_curve_segcount": 0,
          "td_height_ratio": 1.0,
          "td_length_ratio": 0.5,
          "td_maxheight": 2.0,
          "td_maxlen": 1.0,
          "td_target_name": "td_rect_shape",
          "td_width_to_size_filter_ratio": 0.9
        },
        {
          "td_curve_segcount": 0,
          "td_height_ratio": 1.0,
          "td_length_ratio": 0.5,
          "td_maxheight": 2.0,
          "td_maxlen": 1.0,
          "td_target_name": "td_track_end",
          "td_width_to_size_filter_ratio": 0.9
        }
      ],
      "track_widths": [
        0.0,
        0.1,
        0.125,
        0.15,
        0.25,
        0.54,
        0.6
      ],
      "via_dimensions": [
        {
          "diameter": 0.0,
          "drill": 0.0
        },
        {
          "diameter": 0.55,
          "drill": 0.15
        }
      ],
      "zones_allow_external_fillets": false,
      "zones_use_no_outline": true
    },
    "layer_presets": [],
    "viewports": []
  },
  "boards": [],
  "cvpcb": {
    "equivalence_files": []
  },
  "erc": {
    "erc_exclusions": [],
    "meta": {
      "version": 0
    },
    "pin_map": [
      [
        0,
        0,
        0,
        0,
        0,
        0,
        1,
        0,
        0,
        0,
        0,
        2
      ],
      [
        0,
        2,
        0,
        1,
        0,
        0,
        1,
        0,
        2,
        2,
        2,
        2
      ],
      [
        0,
        0,
        0,
        0,
        0,
        0,
        1,
        0,
        1,
        0,
        1,
        2
      ],
      [
        0,
        1,
        0,
        0,
        0,
        0,
        1,
        1,
        2,
        1,
        1,
        2
      ],
      [
        0,
        0,
        0,
        0,
        0,
        0,
        1,
        0,
        0,
        0,
        0,
        2
      ],
      [
        0,
        0,
        0,
        0,
        0,
        0,
        0,
        0,
        0,
        0,
        0,
        2
      ],
      [
        1,
        1,
        1,
        1,
        1,
        0,
        1,
        1,
        1,
        1,
        1,
        2
      ],
      [
        0,
        0,
        0,
        1,
        0,
        0,
        1,
        0,
        0,
        0,
        0,
        2
      ],
      [
        0,
        2,
        1,
        2,
        0,
        0,
        1,
        0,
        2,
        2,
        2,
        2
      ],
      [
        0,
        2,
        0,
        1,
        0,
        0,
        1,
        0,
        2,
        0,
        0,
        2
      ],
      [
        0,
        2,
        1,
        1,
        0,
        0,
        1,
        0,
        2,
        0,
        0,
        2
      ],
      [
        2,
        2,
        2,
        2,
        2,
        2,
        2,
        2,
        2,
        2,
        2,
        2
      ]
    ],
    "rule_severities": {
      "bus_definition_conflict": "error",
      "bus_entry_needed": "error",
      "bus_to_bus_conflict": "error",
      "bus_to_net_conflict": "error",
      "conflicting_netclasses": "error",
      "different_unit_footprint": "error",
      "different_unit_net": "error",
      "duplicate_reference": "error",
      "duplicate_sheet_names": "error",
      "endpoint_off_grid": "warning",
      "extra_units": "error",
      "global_label_dangling": "warning",
      "hier_label_mismatch": "error",
      "label_dangling": "error",
      "lib_symbol_issues": "warning",
      "missing_bidi_pin": "warning",
      "missing_input_pin": "warning",
      "missing_power_pin": "error",
      "missing_unit": "warning",
      "multiple_net_names": "warning",
      "net_not_bus_member": "warning",
      "no_connect_connected": "warning",
      "no_connect_dangling": "warning",
      "pin_not_connected": "error",
      "pin_not_driven": "error",
      "pin_to_pin": "warning",
      "power_pin_not_driven": "error",
      "similar_labels": "warning",
      "simulation_model_issue": "ignore",
      "unannotated": "error",
      "unit_value_mismatch": "error",
      "unresolved_variable": "error",
      "wire_dangling": "error"
    }
  },
  "libraries": {
    "pinned_footprint_libs": [],
    "pinned_symbol_libs": []
  },
  "meta": {
    "filename": "sdi-mipi-bridge.kicad_pro",
    "version": 1
  },
  "net_settings": {
    "classes": [
      {
        "bus_width": 12,
        "clearance": 0.1,
        "diff_pair_gap": 0.1,
        "diff_pair_via_gap": 0.25,
        "diff_pair_width": 0.1,
        "line_style": 0,
        "microvia_diameter": 0.3,
        "microvia_drill": 0.1,
        "name": "Default",
        "pcb_color": "rgba(0, 0, 0, 0.000)",
        "schematic_color": "rgba(0, 0, 0, 0.000)",
        "track_width": 0.1,
        "via_diameter": 0.625,
        "via_drill": 0.15,
        "wire_width": 6
      },
      {
        "bus_width": 12,
        "clearance": 0.1,
        "diff_pair_gap": 0.25,
        "diff_pair_via_gap": 0.25,
        "diff_pair_width": 0.125,
        "line_style": 0,
        "microvia_diameter": 0.3,
        "microvia_drill": 0.1,
        "name": "Inner_Layer",
        "pcb_color": "rgba(0, 0, 0, 0.000)",
        "schematic_color": "rgba(0, 0, 0, 0.000)",
        "track_width": 0.2,
        "via_diameter": 0.625,
        "via_drill": 0.15,
        "wire_width": 6
      }
    ],
    "meta": {
      "version": 3
    },
    "net_colors": null,
    "netclass_assignments": null,
    "netclass_patterns": []
  },
  "pcbnew": {
    "last_paths": {
      "gencad": "",
      "idf": "",
      "netlist": "sdi-mipi-bridge.net",
      "specctra_dsn": "",
      "step": "",
      "vrml": ""
    },
    "page_layout_descr_file": ""
  },
  "schematic": {
    "annotate_start_num": 0,
    "drawing": {
      "dashed_lines_dash_length_ratio": 12.0,
      "dashed_lines_gap_length_ratio": 3.0,
      "default_line_thickness": 6.0,
      "default_text_size": 50.0,
      "field_names": [],
      "intersheets_ref_own_page": false,
      "intersheets_ref_prefix": "",
      "intersheets_ref_short": false,
      "intersheets_ref_show": false,
      "intersheets_ref_suffix": "",
      "junction_size_choice": 3,
      "label_size_ratio": 0.25,
      "pin_symbol_size": 0.0,
      "text_offset_ratio": 0.08
    },
    "legacy_lib_dir": "",
    "legacy_lib_list": [],
    "meta": {
      "version": 1
    },
    "net_format_name": "Pcbnew",
    "ngspice": {
      "fix_include_paths": true,
      "fix_passive_vals": false,
      "meta": {
        "version": 0
      },
      "model_mode": 0,
      "workbook_filename": ""
    },
    "page_layout_descr_file": "",
    "plot_directory": "./doc",
    "spice_adjust_passive_values": false,
    "spice_current_sheet_as_root": false,
    "spice_external_command": "spice \"%I\"",
    "spice_model_current_sheet_as_root": true,
    "spice_save_all_currents": false,
    "spice_save_all_voltages": false,
    "subpart_first_id": 65,
    "subpart_id_separator": 0
  },
  "sheets": [
    [
      "",
      ""
    ]
  ],
  "text_variables": {}
}
